FILE_TYPE = CONNECTIVITY;
{Allegro Design Entry HDL 17.4-2019 S026 (4007227) 1/17/2022}
"PAGE_NUMBER" = 113;
0"NC";
END.
